(kicad_pcb
	(version 20260206)
	(generator "pcbnew")
	(generator_version "10.0")
	(general
		(thickness 1.6)
		(legacy_teardrops no)
	)
	(paper "A4")
	(title_block
		(title "Wiwynn_Tioga_Pass_MB.brd")
		(comment 1 "Tioga Pass / footprints 3262-3269 of 4770")
	)
	(layers
		(0 "F.Cu" signal "TOP")
		(4 "In1.Cu" signal "L2GND")
		(6 "In2.Cu" signal "L3")
		(8 "In3.Cu" signal "L4GND")
		(10 "In4.Cu" signal "L5")
		(12 "In5.Cu" signal "L6GND")
		(14 "In6.Cu" signal "L7VCC")
		(16 "In7.Cu" signal "L8VCC")
		(18 "In8.Cu" signal "L9GND")
		(20 "In9.Cu" signal "L10")
		(22 "In10.Cu" signal "L11GND")
		(24 "In11.Cu" signal "L12")
		(26 "In12.Cu" signal "L13GND")
		(2 "B.Cu" signal "BOTTOM")
		(9 "F.Adhes" user "F.Adhesive")
		(11 "B.Adhes" user "B.Adhesive")
		(13 "F.Paste" user "Package Geometry/Pastemask Top")
		(15 "B.Paste" user "Package Geometry/Pastemask Bottom")
		(5 "F.SilkS" user "Ref Des/Silkscreen Top")
		(7 "B.SilkS" user "Ref Des/Silkscreen Bottom")
		(1 "F.Mask" user "Board Geometry/Soldermask Top")
		(3 "B.Mask" user "Board Geometry/Soldermask Bottom")
		(17 "Dwgs.User" user "User.Drawings")
		(19 "Cmts.User" user "User.Comments")
		(21 "Eco1.User" user "User.Eco1")
		(23 "Eco2.User" user "User.Eco2")
		(25 "Edge.Cuts" user "Board Geometry/Outline")
		(27 "Margin" user)
		(31 "F.CrtYd" user "Package Geometry/Place Bound Top")
		(29 "B.CrtYd" user "Package Geometry/Place Bound Bottom")
		(35 "F.Fab" user "Ref Des/Assembly Top")
		(33 "B.Fab" user "Ref Des/Assembly Bottom")
	)
	(footprint ""
		(layer "B.Cu")
		(at 404.5585 -98.679 -90)
		(property "Reference" "R8C25"
			(at 0 0 90)
			(layer "B.SilkS")
			(hide yes)
			(effects
				(font
					(size 1.27 1.27)
				)
				(justify mirror)
			)
		)
		(property "Value" ""
			(at 0 0 90)
			(layer "B.Fab")
			(effects
				(font
					(size 1.27 1.27)
				)
				(justify mirror)
			)
		)
		(duplicate_pad_numbers_are_jumpers no)
		(fp_poly
			(pts
				(xy 0.2794 -0.1016) (xy -0.2794 -0.1016) (xy -0.2794 0.9906) (xy 0.2794 0.9906)
			)
			(stroke
				(width 0)
				(type default)
			)
			(fill no)
			(layer "B.CrtYd")
		)
		(fp_line
			(start -0.2794 0.9906)
			(end -0.2794 -0.1016)
			(stroke
				(width 0.1)
				(type default)
			)
			(layer "B.Fab")
		)
		(fp_line
			(start 0.2794 0.9906)
			(end -0.2794 0.9906)
			(stroke
				(width 0.1)
				(type default)
			)
			(layer "B.Fab")
		)
		(fp_line
			(start -0.2794 -0.1016)
			(end 0.2794 -0.1016)
			(stroke
				(width 0.1)
				(type default)
			)
			(layer "B.Fab")
		)
		(fp_line
			(start 0.2794 -0.1016)
			(end 0.2794 0.9906)
			(stroke
				(width 0.1)
				(type default)
			)
			(layer "B.Fab")
		)
		(pad "1" smd rect
			(at 0 0 90)
			(size 0.508 0.508)
			(layers "B.Cu" "B.Mask" "B.Paste")
			(net "P3V3_STBY")
		)
		(pad "2" smd rect
			(at 0 0.889 90)
			(size 0.508 0.508)
			(layers "B.Cu" "B.Mask" "B.Paste")
			(net "IRQ_PCH_NIC_ALERT_N")
		)
		(zone
			(layer "B.Cu")
			(hatch none 0.5)
			(connect_pads
				(clearance 0)
			)
			(min_thickness 0.25)
			(keepout
				(tracks not_allowed)
				(vias allowed)
				(pads allowed)
				(copperpour not_allowed)
				(footprints allowed)
			)
			(placement
				(enabled no)
				(sheetname "")
			)
			(fill
				(thermal_gap 0.5)
				(thermal_bridge_width 0.5)
				(island_removal_mode 0)
			)
			(polygon
				(pts
					(xy 403.9235 -98.425) (xy 403.9235 -98.933) (xy 404.3045 -98.933) (xy 404.3045 -98.425)
				)
			)
		)
		(zone
			(layer "B.Cu")
			(hatch none 0.5)
			(connect_pads
				(clearance 0)
			)
			(min_thickness 0.25)
			(keepout
				(tracks allowed)
				(vias not_allowed)
				(pads allowed)
				(copperpour not_allowed)
				(footprints allowed)
			)
			(placement
				(enabled no)
				(sheetname "")
			)
			(fill
				(thermal_gap 0.5)
				(thermal_bridge_width 0.5)
				(island_removal_mode 0)
			)
			(polygon
				(pts
					(xy 404.3045 -98.425) (xy 404.3045 -98.933) (xy 403.9235 -98.933) (xy 403.9235 -98.425)
				)
			)
		)
	)
	(footprint ""
		(layer "B.Cu")
		(at 100.863654 -73.51014)
		(property "Reference" "C8P25"
			(at 0 0 0)
			(layer "B.SilkS")
			(hide yes)
			(effects
				(font
					(size 1.27 1.27)
				)
				(justify mirror)
			)
		)
		(property "Value" ""
			(at 0 0 0)
			(layer "B.Fab")
			(effects
				(font
					(size 1.27 1.27)
				)
				(justify mirror)
			)
		)
		(duplicate_pad_numbers_are_jumpers no)
		(fp_poly
			(pts
				(xy 0.7239 -0.2159) (xy -0.7239 -0.2159) (xy -0.7239 1.9939) (xy 0.7239 1.9939)
			)
			(stroke
				(width 0)
				(type default)
			)
			(fill no)
			(layer "B.CrtYd")
		)
		(fp_line
			(start -0.7239 -0.2159)
			(end 0.7239 -0.2159)
			(stroke
				(width 0.1)
				(type default)
			)
			(layer "B.Fab")
		)
		(fp_line
			(start -0.7239 1.9939)
			(end -0.7239 -0.2159)
			(stroke
				(width 0.1)
				(type default)
			)
			(layer "B.Fab")
		)
		(fp_line
			(start 0.7239 -0.2159)
			(end 0.7239 1.9939)
			(stroke
				(width 0.1)
				(type default)
			)
			(layer "B.Fab")
		)
		(fp_line
			(start 0.7239 1.9939)
			(end -0.7239 1.9939)
			(stroke
				(width 0.1)
				(type default)
			)
			(layer "B.Fab")
		)
		(pad "1" smd rect
			(at 0 0 180)
			(size 1.27 1.016)
			(layers "B.Cu" "B.Mask" "B.Paste")
			(net "PVCCIN_CPU1")
		)
		(pad "2" smd rect
			(at 0 1.778 180)
			(size 1.27 1.016)
			(layers "B.Cu" "B.Mask" "B.Paste")
			(net "GND")
		)
		(zone
			(layer "B.Cu")
			(hatch none 0.5)
			(connect_pads
				(clearance 0)
			)
			(min_thickness 0.25)
			(keepout
				(tracks not_allowed)
				(vias allowed)
				(pads allowed)
				(copperpour not_allowed)
				(footprints allowed)
			)
			(placement
				(enabled no)
				(sheetname "")
			)
			(fill
				(thermal_gap 0.5)
				(thermal_bridge_width 0.5)
				(island_removal_mode 0)
			)
			(polygon
				(pts
					(xy 101.498654 -73.00214) (xy 100.228654 -73.00214) (xy 100.228654 -72.24014) (xy 101.498654 -72.24014)
				)
			)
		)
	)
	(footprint ""
		(layer "B.Cu")
		(at 374.325642 -39.874952 -90)
		(property "Reference" "R2T19"
			(at 0 0 90)
			(layer "B.SilkS")
			(hide yes)
			(effects
				(font
					(size 1.27 1.27)
				)
				(justify mirror)
			)
		)
		(property "Value" ""
			(at 0 0 90)
			(layer "B.Fab")
			(effects
				(font
					(size 1.27 1.27)
				)
				(justify mirror)
			)
		)
		(duplicate_pad_numbers_are_jumpers no)
		(fp_poly
			(pts
				(xy 0.2794 -0.1016) (xy -0.2794 -0.1016) (xy -0.2794 0.9906) (xy 0.2794 0.9906)
			)
			(stroke
				(width 0)
				(type default)
			)
			(fill no)
			(layer "B.CrtYd")
		)
		(fp_line
			(start -0.2794 0.9906)
			(end -0.2794 -0.1016)
			(stroke
				(width 0.1)
				(type default)
			)
			(layer "B.Fab")
		)
		(fp_line
			(start 0.2794 0.9906)
			(end -0.2794 0.9906)
			(stroke
				(width 0.1)
				(type default)
			)
			(layer "B.Fab")
		)
		(fp_line
			(start -0.2794 -0.1016)
			(end 0.2794 -0.1016)
			(stroke
				(width 0.1)
				(type default)
			)
			(layer "B.Fab")
		)
		(fp_line
			(start 0.2794 -0.1016)
			(end 0.2794 0.9906)
			(stroke
				(width 0.1)
				(type default)
			)
			(layer "B.Fab")
		)
		(pad "1" smd rect
			(at 0 0 90)
			(size 0.508 0.508)
			(layers "B.Cu" "B.Mask" "B.Paste")
			(net "PVCCIO_CPU0")
		)
		(pad "2" smd rect
			(at 0 0.889 90)
			(size 0.508 0.508)
			(layers "B.Cu" "B.Mask" "B.Paste")
			(net "H_CPU_ERR0_GTL_R_N")
		)
		(zone
			(layer "B.Cu")
			(hatch none 0.5)
			(connect_pads
				(clearance 0)
			)
			(min_thickness 0.25)
			(keepout
				(tracks not_allowed)
				(vias allowed)
				(pads allowed)
				(copperpour not_allowed)
				(footprints allowed)
			)
			(placement
				(enabled no)
				(sheetname "")
			)
			(fill
				(thermal_gap 0.5)
				(thermal_bridge_width 0.5)
				(island_removal_mode 0)
			)
			(polygon
				(pts
					(xy 373.690642 -39.620952) (xy 373.690642 -40.128952) (xy 374.071642 -40.128952) (xy 374.071642 -39.620952)
				)
			)
		)
		(zone
			(layer "B.Cu")
			(hatch none 0.5)
			(connect_pads
				(clearance 0)
			)
			(min_thickness 0.25)
			(keepout
				(tracks allowed)
				(vias not_allowed)
				(pads allowed)
				(copperpour not_allowed)
				(footprints allowed)
			)
			(placement
				(enabled no)
				(sheetname "")
			)
			(fill
				(thermal_gap 0.5)
				(thermal_bridge_width 0.5)
				(island_removal_mode 0)
			)
			(polygon
				(pts
					(xy 374.071642 -39.620952) (xy 374.071642 -40.128952) (xy 373.690642 -40.128952) (xy 373.690642 -39.620952)
				)
			)
		)
	)
	(footprint ""
		(layer "B.Cu")
		(at 352.8949 -72.0344 -90)
		(property "Reference" "R7D39"
			(at 0 0 90)
			(layer "B.SilkS")
			(hide yes)
			(effects
				(font
					(size 1.27 1.27)
				)
				(justify mirror)
			)
		)
		(property "Value" ""
			(at 0 0 90)
			(layer "B.Fab")
			(effects
				(font
					(size 1.27 1.27)
				)
				(justify mirror)
			)
		)
		(duplicate_pad_numbers_are_jumpers no)
		(fp_poly
			(pts
				(xy 0.2794 -0.1016) (xy -0.2794 -0.1016) (xy -0.2794 0.9906) (xy 0.2794 0.9906)
			)
			(stroke
				(width 0)
				(type default)
			)
			(fill no)
			(layer "B.CrtYd")
		)
		(fp_line
			(start -0.2794 0.9906)
			(end -0.2794 -0.1016)
			(stroke
				(width 0.1)
				(type default)
			)
			(layer "B.Fab")
		)
		(fp_line
			(start 0.2794 0.9906)
			(end -0.2794 0.9906)
			(stroke
				(width 0.1)
				(type default)
			)
			(layer "B.Fab")
		)
		(fp_line
			(start -0.2794 -0.1016)
			(end 0.2794 -0.1016)
			(stroke
				(width 0.1)
				(type default)
			)
			(layer "B.Fab")
		)
		(fp_line
			(start 0.2794 -0.1016)
			(end 0.2794 0.9906)
			(stroke
				(width 0.1)
				(type default)
			)
			(layer "B.Fab")
		)
		(pad "1" smd rect
			(at 0 0 90)
			(size 0.508 0.508)
			(layers "B.Cu" "B.Mask" "B.Paste")
			(net "FM_CPU0_VRM_OSC_EN")
		)
		(pad "2" smd rect
			(at 0 0.889 90)
			(size 0.508 0.508)
			(layers "B.Cu" "B.Mask" "B.Paste")
			(net "FM_CPU0_VRM_322M_156M_OSC_EN")
		)
		(zone
			(layer "B.Cu")
			(hatch none 0.5)
			(connect_pads
				(clearance 0)
			)
			(min_thickness 0.25)
			(keepout
				(tracks not_allowed)
				(vias allowed)
				(pads allowed)
				(copperpour not_allowed)
				(footprints allowed)
			)
			(placement
				(enabled no)
				(sheetname "")
			)
			(fill
				(thermal_gap 0.5)
				(thermal_bridge_width 0.5)
				(island_removal_mode 0)
			)
			(polygon
				(pts
					(xy 352.2599 -71.7804) (xy 352.2599 -72.2884) (xy 352.6409 -72.2884) (xy 352.6409 -71.7804)
				)
			)
		)
		(zone
			(layer "B.Cu")
			(hatch none 0.5)
			(connect_pads
				(clearance 0)
			)
			(min_thickness 0.25)
			(keepout
				(tracks allowed)
				(vias not_allowed)
				(pads allowed)
				(copperpour not_allowed)
				(footprints allowed)
			)
			(placement
				(enabled no)
				(sheetname "")
			)
			(fill
				(thermal_gap 0.5)
				(thermal_bridge_width 0.5)
				(island_removal_mode 0)
			)
			(polygon
				(pts
					(xy 352.6409 -71.7804) (xy 352.6409 -72.2884) (xy 352.2599 -72.2884) (xy 352.2599 -71.7804)
				)
			)
		)
	)
	(footprint ""
		(layer "B.Cu")
		(at 113.575592 -69.809614 -90)
		(property "Reference" "C7P18"
			(at 0 0 90)
			(layer "B.SilkS")
			(hide yes)
			(effects
				(font
					(size 1.27 1.27)
				)
				(justify mirror)
			)
		)
		(property "Value" ""
			(at 0 0 90)
			(layer "B.Fab")
			(effects
				(font
					(size 1.27 1.27)
				)
				(justify mirror)
			)
		)
		(duplicate_pad_numbers_are_jumpers no)
		(fp_poly
			(pts
				(xy 0.7239 -0.2159) (xy -0.7239 -0.2159) (xy -0.7239 1.9939) (xy 0.7239 1.9939)
			)
			(stroke
				(width 0)
				(type default)
			)
			(fill no)
			(layer "B.CrtYd")
		)
		(fp_line
			(start -0.7239 1.9939)
			(end -0.7239 -0.2159)
			(stroke
				(width 0.1)
				(type default)
			)
			(layer "B.Fab")
		)
		(fp_line
			(start 0.7239 1.9939)
			(end -0.7239 1.9939)
			(stroke
				(width 0.1)
				(type default)
			)
			(layer "B.Fab")
		)
		(fp_line
			(start -0.7239 -0.2159)
			(end 0.7239 -0.2159)
			(stroke
				(width 0.1)
				(type default)
			)
			(layer "B.Fab")
		)
		(fp_line
			(start 0.7239 -0.2159)
			(end 0.7239 1.9939)
			(stroke
				(width 0.1)
				(type default)
			)
			(layer "B.Fab")
		)
		(pad "1" smd rect
			(at 0 0 90)
			(size 1.27 1.016)
			(layers "B.Cu" "B.Mask" "B.Paste")
			(net "PVCCIO_CPU1")
		)
		(pad "2" smd rect
			(at 0 1.778 90)
			(size 1.27 1.016)
			(layers "B.Cu" "B.Mask" "B.Paste")
			(net "GND")
		)
		(zone
			(layer "B.Cu")
			(hatch none 0.5)
			(connect_pads
				(clearance 0)
			)
			(min_thickness 0.25)
			(keepout
				(tracks not_allowed)
				(vias allowed)
				(pads allowed)
				(copperpour not_allowed)
				(footprints allowed)
			)
			(placement
				(enabled no)
				(sheetname "")
			)
			(fill
				(thermal_gap 0.5)
				(thermal_bridge_width 0.5)
				(island_removal_mode 0)
			)
			(polygon
				(pts
					(xy 113.067592 -69.174614) (xy 113.067592 -70.444614) (xy 112.305592 -70.444614) (xy 112.305592 -69.174614)
				)
			)
		)
	)
	(footprint ""
		(layer "B.Cu")
		(at 400.31416 -54.25186)
		(property "Reference" "R3T3"
			(at 0 0 0)
			(layer "B.SilkS")
			(hide yes)
			(effects
				(font
					(size 1.27 1.27)
				)
				(justify mirror)
			)
		)
		(property "Value" ""
			(at 0 0 0)
			(layer "B.Fab")
			(effects
				(font
					(size 1.27 1.27)
				)
				(justify mirror)
			)
		)
		(duplicate_pad_numbers_are_jumpers no)
		(fp_poly
			(pts
				(xy 0.2794 -0.1016) (xy -0.2794 -0.1016) (xy -0.2794 0.9906) (xy 0.2794 0.9906)
			)
			(stroke
				(width 0)
				(type default)
			)
			(fill no)
			(layer "B.CrtYd")
		)
		(fp_line
			(start -0.2794 -0.1016)
			(end 0.2794 -0.1016)
			(stroke
				(width 0.1)
				(type default)
			)
			(layer "B.Fab")
		)
		(fp_line
			(start -0.2794 0.9906)
			(end -0.2794 -0.1016)
			(stroke
				(width 0.1)
				(type default)
			)
			(layer "B.Fab")
		)
		(fp_line
			(start 0.2794 -0.1016)
			(end 0.2794 0.9906)
			(stroke
				(width 0.1)
				(type default)
			)
			(layer "B.Fab")
		)
		(fp_line
			(start 0.2794 0.9906)
			(end -0.2794 0.9906)
			(stroke
				(width 0.1)
				(type default)
			)
			(layer "B.Fab")
		)
		(pad "1" smd rect
			(at 0 0 180)
			(size 0.508 0.508)
			(layers "B.Cu" "B.Mask" "B.Paste")
			(net "P3V3_STBY")
		)
		(pad "2" smd rect
			(at 0 0.889 180)
			(size 0.508 0.508)
			(layers "B.Cu" "B.Mask" "B.Paste")
			(net "PU_SPI1_RST")
		)
		(zone
			(layer "B.Cu")
			(hatch none 0.5)
			(connect_pads
				(clearance 0)
			)
			(min_thickness 0.25)
			(keepout
				(tracks allowed)
				(vias not_allowed)
				(pads allowed)
				(copperpour not_allowed)
				(footprints allowed)
			)
			(placement
				(enabled no)
				(sheetname "")
			)
			(fill
				(thermal_gap 0.5)
				(thermal_bridge_width 0.5)
				(island_removal_mode 0)
			)
			(polygon
				(pts
					(xy 400.56816 -53.99786) (xy 400.06016 -53.99786) (xy 400.06016 -53.61686) (xy 400.56816 -53.61686)
				)
			)
		)
		(zone
			(layer "B.Cu")
			(hatch none 0.5)
			(connect_pads
				(clearance 0)
			)
			(min_thickness 0.25)
			(keepout
				(tracks not_allowed)
				(vias allowed)
				(pads allowed)
				(copperpour not_allowed)
				(footprints allowed)
			)
			(placement
				(enabled no)
				(sheetname "")
			)
			(fill
				(thermal_gap 0.5)
				(thermal_bridge_width 0.5)
				(island_removal_mode 0)
			)
			(polygon
				(pts
					(xy 400.56816 -53.61686) (xy 400.06016 -53.61686) (xy 400.06016 -53.99786) (xy 400.56816 -53.99786)
				)
			)
		)
	)
	(footprint ""
		(layer "B.Cu")
		(at 192.659 -144.4752 180)
		(property "Reference" "R6L14"
			(at 0 0 0)
			(layer "B.SilkS")
			(hide yes)
			(effects
				(font
					(size 1.27 1.27)
				)
				(justify mirror)
			)
		)
		(property "Value" ""
			(at 0 0 0)
			(layer "B.Fab")
			(effects
				(font
					(size 1.27 1.27)
				)
				(justify mirror)
			)
		)
		(duplicate_pad_numbers_are_jumpers no)
		(fp_poly
			(pts
				(xy 0.2794 -0.1016) (xy -0.2794 -0.1016) (xy -0.2794 0.9906) (xy 0.2794 0.9906)
			)
			(stroke
				(width 0)
				(type default)
			)
			(fill no)
			(layer "B.CrtYd")
		)
		(fp_line
			(start 0.2794 0.9906)
			(end -0.2794 0.9906)
			(stroke
				(width 0.1)
				(type default)
			)
			(layer "B.Fab")
		)
		(fp_line
			(start 0.2794 -0.1016)
			(end 0.2794 0.9906)
			(stroke
				(width 0.1)
				(type default)
			)
			(layer "B.Fab")
		)
		(fp_line
			(start -0.2794 0.9906)
			(end -0.2794 -0.1016)
			(stroke
				(width 0.1)
				(type default)
			)
			(layer "B.Fab")
		)
		(fp_line
			(start -0.2794 -0.1016)
			(end 0.2794 -0.1016)
			(stroke
				(width 0.1)
				(type default)
			)
			(layer "B.Fab")
		)
		(pad "1" smd rect
			(at 0 0)
			(size 0.508 0.508)
			(layers "B.Cu" "B.Mask" "B.Paste")
			(net "M_E_CPU_VREF")
		)
		(pad "2" smd rect
			(at 0 0.889)
			(size 0.508 0.508)
			(layers "B.Cu" "B.Mask" "B.Paste")
			(net "M_E_VREF")
		)
		(zone
			(layer "B.Cu")
			(hatch none 0.5)
			(connect_pads
				(clearance 0)
			)
			(min_thickness 0.25)
			(keepout
				(tracks not_allowed)
				(vias allowed)
				(pads allowed)
				(copperpour not_allowed)
				(footprints allowed)
			)
			(placement
				(enabled no)
				(sheetname "")
			)
			(fill
				(thermal_gap 0.5)
				(thermal_bridge_width 0.5)
				(island_removal_mode 0)
			)
			(polygon
				(pts
					(xy 192.405 -145.1102) (xy 192.913 -145.1102) (xy 192.913 -144.7292) (xy 192.405 -144.7292)
				)
			)
		)
		(zone
			(layer "B.Cu")
			(hatch none 0.5)
			(connect_pads
				(clearance 0)
			)
			(min_thickness 0.25)
			(keepout
				(tracks allowed)
				(vias not_allowed)
				(pads allowed)
				(copperpour not_allowed)
				(footprints allowed)
			)
			(placement
				(enabled no)
				(sheetname "")
			)
			(fill
				(thermal_gap 0.5)
				(thermal_bridge_width 0.5)
				(island_removal_mode 0)
			)
			(polygon
				(pts
					(xy 192.405 -144.7292) (xy 192.913 -144.7292) (xy 192.913 -145.1102) (xy 192.405 -145.1102)
				)
			)
		)
	)
	(footprint ""
		(layer "B.Cu")
		(at 442.669168 -146.875754 90)
		(property "Reference" "R25W180"
			(at 0.8382 -0.67818 90)
			(unlocked yes)
			(layer "B.SilkS")
			(effects
				(font
					(size 0.4064 0.254)
					(thickness 0.1524)
				)
				(justify left mirror)
			)
		)
		(property "Value" ""
			(at 0 0 90)
			(layer "B.Fab")
			(effects
				(font
					(size 1.27 1.27)
				)
				(justify mirror)
			)
		)
		(duplicate_pad_numbers_are_jumpers no)
		(fp_poly
			(pts
				(xy 0.2794 -0.1016) (xy -0.2794 -0.1016) (xy -0.2794 0.9906) (xy 0.2794 0.9906)
			)
			(stroke
				(width 0)
				(type default)
			)
			(fill no)
			(layer "B.CrtYd")
		)
		(fp_line
			(start 0.2794 -0.1016)
			(end 0.2794 0.9906)
			(stroke
				(width 0.1)
				(type default)
			)
			(layer "B.Fab")
		)
		(fp_line
			(start -0.2794 -0.1016)
			(end 0.2794 -0.1016)
			(stroke
				(width 0.1)
				(type default)
			)
			(layer "B.Fab")
		)
		(fp_line
			(start 0.2794 0.9906)
			(end -0.2794 0.9906)
			(stroke
				(width 0.1)
				(type default)
			)
			(layer "B.Fab")
		)
		(fp_line
			(start -0.2794 0.9906)
			(end -0.2794 -0.1016)
			(stroke
				(width 0.1)
				(type default)
			)
			(layer "B.Fab")
		)
		(pad "1" smd rect
			(at 0 0 270)
			(size 0.508 0.508)
			(layers "B.Cu" "B.Mask" "B.Paste")
			(net "P3V3_STBY")
		)
		(pad "2" smd rect
			(at 0 0.889 270)
			(size 0.508 0.508)
			(layers "B.Cu" "B.Mask" "B.Paste")
			(net "BMC_DEBUG_EN_N")
		)
		(zone
			(layer "B.Cu")
			(hatch none 0.5)
			(connect_pads
				(clearance 0)
			)
			(min_thickness 0.25)
			(keepout
				(tracks allowed)
				(vias not_allowed)
				(pads allowed)
				(copperpour not_allowed)
				(footprints allowed)
			)
			(placement
				(enabled no)
				(sheetname "")
			)
			(fill
				(thermal_gap 0.5)
				(thermal_bridge_width 0.5)
				(island_removal_mode 0)
			)
			(polygon
				(pts
					(xy 442.923168 -147.129754) (xy 442.923168 -146.621754) (xy 443.304168 -146.621754) (xy 443.304168 -147.129754)
				)
			)
		)
		(zone
			(layer "B.Cu")
			(hatch none 0.5)
			(connect_pads
				(clearance 0)
			)
			(min_thickness 0.25)
			(keepout
				(tracks not_allowed)
				(vias allowed)
				(pads allowed)
				(copperpour not_allowed)
				(footprints allowed)
			)
			(placement
				(enabled no)
				(sheetname "")
			)
			(fill
				(thermal_gap 0.5)
				(thermal_bridge_width 0.5)
				(island_removal_mode 0)
			)
			(polygon
				(pts
					(xy 443.304168 -147.129754) (xy 443.304168 -146.621754) (xy 442.923168 -146.621754) (xy 442.923168 -147.129754)
				)
			)
		)
	)
)
